# T6G (Grand Teton) — schematic netlist excerpt (pin names and nets, part order shuffled) for the footprints in the layout excerpt that follows; sources: Cadence DE-HDL packaged netlist, KiCad conversion of 04192023_DAF0TMB3IC0_F0TG_MB_C_brd_V02_OCP.brd

R6316  Q_RES  0 5% CHIP  pkg 0402LF  page 178 : A = USB_HUB2_TI_USB_VBUS ; B = USB_HUB2_TI_USB_VBUS_MRP_RESET_N
PC188  Q_CAP  560PF 50V 10% EMPTY  pkg C0402  page 199 : A = SW_PVDDCR_SOC_P0_SW3 ; B = SW_PVDDCR_SOC_P0_SW3_RC

(kicad_pcb
	(version 20260206)
	(generator "pcbnew")
	(generator_version "10.0")
	(general
		(thickness 1.6)
		(legacy_teardrops no)
	)
	(paper "A4")
	(title_block
		(title "04192023_DAF0TMB3IC0_F0TG_MB_C_brd_V02_OCP.brd")
		(comment 1 "Grand Teton / footprints 4056-4057 of 8354")
	)
	(layers
		(0 "F.Cu" signal "TOP")
		(4 "In1.Cu" signal "GND")
		(6 "In2.Cu" signal "IN1")
		(8 "In3.Cu" signal "GND1")
		(10 "In4.Cu" signal "IN2")
		(12 "In5.Cu" signal "GND2")
		(14 "In6.Cu" signal "IN3")
		(16 "In7.Cu" signal "GND3")
		(18 "In8.Cu" signal "VCC")
		(20 "In9.Cu" signal "VCC1")
		(22 "In10.Cu" signal "GND4")
		(24 "In11.Cu" signal "IN4")
		(26 "In12.Cu" signal "GND5")
		(28 "In13.Cu" signal "IN5")
		(30 "In14.Cu" signal "GND6")
		(32 "In15.Cu" signal "IN6")
		(34 "In16.Cu" signal "GND7")
		(2 "B.Cu" signal "BOTTOM")
		(9 "F.Adhes" user "F.Adhesive")
		(11 "B.Adhes" user "B.Adhesive")
		(13 "F.Paste" user "Package Geometry/Pastemask Top")
		(15 "B.Paste" user "Package Geometry/Pastemask Bottom")
		(5 "F.SilkS" user "Ref Des/Silkscreen Top")
		(7 "B.SilkS" user "Ref Des/Silkscreen Bottom")
		(1 "F.Mask" user "Board Geometry/Soldermask Top")
		(3 "B.Mask" user "Board Geometry/Soldermask Bottom")
		(17 "Dwgs.User" user "User.Drawings")
		(19 "Cmts.User" user "User.Comments")
		(21 "Eco1.User" user "User.Eco1")
		(23 "Eco2.User" user "User.Eco2")
		(25 "Edge.Cuts" user "Board Geometry/Outline")
		(27 "Margin" user)
		(31 "F.CrtYd" user "Package Geometry/Place Bound Top")
		(29 "B.CrtYd" user "Package Geometry/Place Bound Bottom")
		(35 "F.Fab" user "Ref Des/Assembly Top")
		(33 "B.Fab" user "Ref Des/Assembly Bottom")
	)
	(footprint ""
		(layer "F.Cu")
		(at 418.2237 -166.772082)
		(property "Reference" "PC188"
			(at 0 0 0)
			(layer "F.SilkS")
			(hide yes)
			(effects
				(font
					(size 1.27 1.27)
				)
			)
		)
		(property "Value" ""
			(at 0 0 0)
			(layer "F.Fab")
			(effects
				(font
					(size 1.27 1.27)
				)
			)
		)
		(duplicate_pad_numbers_are_jumpers no)
		(fp_line
			(start -0.7874 -0.4064)
			(end 0.7874 -0.4064)
			(stroke
				(width 0.1524)
				(type default)
			)
			(layer "F.SilkS")
		)
		(fp_line
			(start -0.7874 0.4064)
			(end -0.7874 -0.4064)
			(stroke
				(width 0.1524)
				(type default)
			)
			(layer "F.SilkS")
		)
		(fp_line
			(start 0.7874 -0.4064)
			(end 0.7874 0.4064)
			(stroke
				(width 0.1524)
				(type default)
			)
			(layer "F.SilkS")
		)
		(fp_line
			(start 0.7874 0.4064)
			(end -0.7874 0.4064)
			(stroke
				(width 0.1524)
				(type default)
			)
			(layer "F.SilkS")
		)
		(fp_line
			(start -0.67945 -0.305054)
			(end -0.12065 -0.305054)
			(stroke
				(width 0.1)
				(type default)
			)
			(layer "F.Fab")
		)
		(fp_line
			(start -0.67945 0.3048)
			(end -0.67945 -0.305054)
			(stroke
				(width 0.1)
				(type default)
			)
			(layer "F.Fab")
		)
		(fp_line
			(start -0.12065 -0.305054)
			(end -0.12065 -0.2794)
			(stroke
				(width 0.1)
				(type default)
			)
			(layer "F.Fab")
		)
		(fp_line
			(start -0.12065 -0.2794)
			(end 0.12065 -0.2794)
			(stroke
				(width 0.1)
				(type default)
			)
			(layer "F.Fab")
		)
		(fp_line
			(start -0.12065 0.2794)
			(end -0.12065 0.3048)
			(stroke
				(width 0.1)
				(type default)
			)
			(layer "F.Fab")
		)
		(fp_line
			(start -0.12065 0.3048)
			(end -0.67945 0.3048)
			(stroke
				(width 0.1)
				(type default)
			)
			(layer "F.Fab")
		)
		(fp_line
			(start 0.120396 0.2794)
			(end -0.12065 0.2794)
			(stroke
				(width 0.1)
				(type default)
			)
			(layer "F.Fab")
		)
		(fp_line
			(start 0.120396 0.3048)
			(end 0.120396 0.2794)
			(stroke
				(width 0.1)
				(type default)
			)
			(layer "F.Fab")
		)
		(fp_line
			(start 0.12065 -0.3048)
			(end 0.67945 -0.3048)
			(stroke
				(width 0.1)
				(type default)
			)
			(layer "F.Fab")
		)
		(fp_line
			(start 0.12065 -0.2794)
			(end 0.12065 -0.3048)
			(stroke
				(width 0.1)
				(type default)
			)
			(layer "F.Fab")
		)
		(fp_line
			(start 0.67945 -0.3048)
			(end 0.67945 0.3048)
			(stroke
				(width 0.1)
				(type default)
			)
			(layer "F.Fab")
		)
		(fp_line
			(start 0.67945 0.3048)
			(end 0.120396 0.3048)
			(stroke
				(width 0.1)
				(type default)
			)
			(layer "F.Fab")
		)
		(pad "1" smd circle
			(at -0.40005 0)
			(size 0 0)
			(layers "F.Cu" "F.Mask" "F.Paste")
			(net "SW_PVDDCR_SOC_P0_SW3")
		)
		(pad "2" smd circle
			(at 0.40005 0)
			(size 0 0)
			(layers "F.Cu" "F.Mask" "F.Paste")
			(net "SW_PVDDCR_SOC_P0_SW3_RC")
		)
	)
	(footprint ""
		(layer "F.Cu")
		(at 103.453946 -52.86248 -90)
		(property "Reference" "R6316"
			(at 0 0 270)
			(layer "F.SilkS")
			(hide yes)
			(effects
				(font
					(size 1.27 1.27)
				)
			)
		)
		(property "Value" ""
			(at 0 0 270)
			(layer "F.Fab")
			(effects
				(font
					(size 1.27 1.27)
				)
			)
		)
		(duplicate_pad_numbers_are_jumpers no)
		(fp_line
			(start -0.7874 0.4064)
			(end -0.7874 -0.4064)
			(stroke
				(width 0.1524)
				(type default)
			)
			(layer "F.SilkS")
		)
		(fp_line
			(start 0.7874 0.4064)
			(end -0.7874 0.4064)
			(stroke
				(width 0.1524)
				(type default)
			)
			(layer "F.SilkS")
		)
		(fp_line
			(start -0.7874 -0.4064)
			(end 0.7874 -0.4064)
			(stroke
				(width 0.1524)
				(type default)
			)
			(layer "F.SilkS")
		)
		(fp_line
			(start 0.7874 -0.4064)
			(end 0.7874 0.4064)
			(stroke
				(width 0.1524)
				(type default)
			)
			(layer "F.SilkS")
		)
		(fp_line
			(start -0.67945 0.3048)
			(end -0.67945 -0.305054)
			(stroke
				(width 0.1)
				(type default)
			)
			(layer "F.Fab")
		)
		(fp_line
			(start -0.12065 0.3048)
			(end -0.67945 0.3048)
			(stroke
				(width 0.1)
				(type default)
			)
			(layer "F.Fab")
		)
		(fp_line
			(start 0.120396 0.3048)
			(end 0.120396 0.2794)
			(stroke
				(width 0.1)
				(type default)
			)
			(layer "F.Fab")
		)
		(fp_line
			(start 0.67945 0.3048)
			(end 0.120396 0.3048)
			(stroke
				(width 0.1)
				(type default)
			)
			(layer "F.Fab")
		)
		(fp_line
			(start -0.12065 0.2794)
			(end -0.12065 0.3048)
			(stroke
				(width 0.1)
				(type default)
			)
			(layer "F.Fab")
		)
		(fp_line
			(start 0.120396 0.2794)
			(end -0.12065 0.2794)
			(stroke
				(width 0.1)
				(type default)
			)
			(layer "F.Fab")
		)
		(fp_line
			(start -0.12065 -0.2794)
			(end 0.12065 -0.2794)
			(stroke
				(width 0.1)
				(type default)
			)
			(layer "F.Fab")
		)
		(fp_line
			(start 0.12065 -0.2794)
			(end 0.12065 -0.3048)
			(stroke
				(width 0.1)
				(type default)
			)
			(layer "F.Fab")
		)
		(fp_line
			(start 0.12065 -0.3048)
			(end 0.67945 -0.3048)
			(stroke
				(width 0.1)
				(type default)
			)
			(layer "F.Fab")
		)
		(fp_line
			(start 0.67945 -0.3048)
			(end 0.67945 0.3048)
			(stroke
				(width 0.1)
				(type default)
			)
			(layer "F.Fab")
		)
		(fp_line
			(start -0.67945 -0.305054)
			(end -0.12065 -0.305054)
			(stroke
				(width 0.1)
				(type default)
			)
			(layer "F.Fab")
		)
		(fp_line
			(start -0.12065 -0.305054)
			(end -0.12065 -0.2794)
			(stroke
				(width 0.1)
				(type default)
			)
			(layer "F.Fab")
		)
		(pad "1" smd circle
			(at -0.40005 0 270)
			(size 0 0)
			(layers "F.Cu" "F.Mask" "F.Paste")
			(net "USB_HUB2_TI_USB_VBUS")
		)
		(pad "2" smd circle
			(at 0.40005 0 270)
			(size 0 0)
			(layers "F.Cu" "F.Mask" "F.Paste")
			(net "USB_HUB2_TI_USB_VBUS_MRP_RESET_N")
		)
	)
)
